;LEADER: 12 
;HEADER: 
;CODE  : ASCII 
;FILE  : 9049_F0T_FAN_BOARD_MP5048_D_v02_20221209_0830-1-6.drl for  ... layers TOP and BOTTOM
;DESIGN: 9049_F0T_FAN_BOARD_MP5048_D_v02_20221209_0830.brd
;   Holesize 1. = 10.000000 Tolerance = +0.000000/-10.000000 PLATED MILS Quantity = 1489
;   Holesize 2. = 38.000000 Tolerance = +2.000000/-2.000000 PLATED MILS Quantity = 128
;   Holesize 3. = 67.000000 Tolerance = +3.000000/-3.000000 PLATED MILS Quantity = 12
;   Holesize 4. = 119.000000 Tolerance = +3.000000/-3.000000 PLATED MILS Quantity = 4
;   Holesize 5. = 252.000000 Tolerance = +4.000000/-4.000000 PLATED MILS Quantity = 1
;   Holesize 6. = 59.000000 Tolerance = +2.000000/-2.000000 NON_PLATED MILS Quantity = 8
;   Holesize 7. = 125.000000 Tolerance = +2.000000/-0.000000 NON_PLATED MILS Quantity = 3
%
G90
X0141748Y0026922
X0146740Y0003016
X0165799Y0003002
X0185799Y0003002
X0199120Y0009903
X0132500Y0099000
X0127500Y0129500
X0135750Y0132750
X0123500Y0059500
X0122500Y0102000
X0138650Y0094000
X0142000Y0074575
X0123500Y0115500
X0142000Y0098842
X0137449Y0113340
X0142500Y0103342
X0127000Y0077500
X0135000Y0120500
X0132350Y0094273
X0125917Y0037300
X0122917Y0037300
X0125917Y0039800
X0122917Y0039800
X0125500Y0118000
X0141327Y0115542
X0134525Y0107842
X0142727Y0094000
X0142727Y0079842
X0135500Y0070441
X0112500Y0076000
X0125917Y0042300
X0122917Y0042300
X0125917Y0044800
X0122917Y0044800
X0125917Y0047300
X0122917Y0047300
X0125917Y0049800
X0122917Y0049800
X0114500Y0127000
X0135014Y0050977
X0114522Y0042300
X0111522Y0042300
X0114522Y0039800
X0111522Y0039800
X0114522Y0047300
X0111522Y0052300
X0114522Y0052300
X0114522Y0049800
X0111522Y0049800
X0111522Y0047300
X0114522Y0044800
X0111522Y0044800
X0115918Y0075650
X0112000Y0088700
X0118475Y0083500
X0103000Y0136500
X0138238Y0229444
X0140818Y0229444
X0143358Y0229444
X0143358Y0231944
X0140778Y0231944
X0138198Y0231944
X0168564Y0214543
X0168564Y0217543
X0164864Y0205443
X0164864Y0208443
X0164964Y0196543
X0164964Y0199543
X0165164Y0189143
X0165164Y0186143
X0149664Y0165443
X0149664Y0168443
X0149664Y0171443
X0149664Y0174443
X0154576Y0149149
X0154576Y0146649
X0148576Y0149149
X0151576Y0149149
X0151576Y0146649
X0148576Y0146649
X0186764Y0205743
X0186764Y0208743
X0183582Y0214228
X0183582Y0217228
X0186964Y0196543
X0186964Y0199543
X0186964Y0186043
X0186964Y0189043
X0189664Y0173843
X0192164Y0173843
X0189664Y0170843
X0192164Y0170843
X0189664Y0167843
X0192164Y0167843
X0189664Y0164843
X0192164Y0164843
X0191219Y0157489
X0193719Y0157489
X0155562Y0235093
X0152982Y0235093
X0150482Y0235093
X0185358Y0227328
X0182358Y0227328
X0185358Y0230328
X0182358Y0230328
X0179358Y0227328
X0179358Y0230328
X0163022Y0230593
X0165562Y0230593
X0155562Y0232593
X0150482Y0232593
X0153022Y0232593
X0168982Y0317012
X0171522Y0317012
X0174062Y0317012
X0174062Y0314512
X0171562Y0314512
X0168982Y0314512
X0144600Y0337100
X0158858Y0332228
X0158858Y0329228
X0162783Y0301463
X0160777Y0275688
X0167858Y0279310
X0169358Y0286228
X0137495Y0248875
X0128000Y0251000
X0159430Y0244830
X0161200Y0251200
X0152500Y0249501
X0141890Y0246451
X0186967Y0253728
X0183967Y0253728
X0177967Y0253728
X0180967Y0253728
X0178067Y0256528
X0187067Y0256528
X0184067Y0256528
X0181067Y0256528
X0164296Y0297723
X0149000Y0250000
X0162858Y0244728
X0165858Y0244728
X0178258Y0269528
X0187258Y0269528
X0184258Y0269528
X0181258Y0269528
X0155482Y0266228
X0145982Y0268287
X0139435Y0266728
X0149482Y0301728
X0146482Y0301728
X0183458Y0335828
X0186458Y0335828
X0180458Y0335828
X0177458Y0335828
X0172905Y0279728
X0166499Y0276483
X0156858Y0280228
X0136482Y0286228
X0130482Y0286228
X0133482Y0286228
X0136482Y0289228
X0130482Y0289228
X0133482Y0289228
X0127482Y0286228
X0127482Y0289228
X0127482Y0312228
X0127482Y0315228
X0149482Y0316228
X0146482Y0316228
X0130482Y0312228
X0130482Y0315228
X0133482Y0312228
X0133482Y0315228
X0159358Y0311363
X0161858Y0311363
X0161858Y0313863
X0159318Y0313863
X0156778Y0313863
X0156778Y0311363
X0179658Y0243528
X0182658Y0243528
X0185658Y0243528
X0150500Y0247000
X0142400Y0269800
X0144482Y0265728
X0136500Y0261000
X0183500Y0299500
X0167000Y0296310
X0152420Y0296500
X0170358Y0298858
X0160000Y0298500
X0149500Y0295500
X0173858Y0298500
X0147393Y0265728
X0164947Y0280728
X0136482Y0272471
X0175858Y0273985
X0149769Y0283287
X0178811Y0281071
X0133529Y0265385
X0161105Y0266081
X0165014Y0268287
X0147500Y0278228
X0117500Y0398500
X0179858Y0362290
X0179858Y0359790
X0185858Y0362290
X0182858Y0362290
X0182858Y0359790
X0185858Y0359790
X0176858Y0362290
X0176858Y0359790
X0149900Y0364300
X0149900Y0367528
X0149900Y0370300
X0144600Y0339828
X0149900Y0351800
X0149900Y0349028
X0149900Y0346300
X0139150Y0429650
X0139150Y0420193
X0110000Y0392500
X0107966Y0408260
X0130500Y0432500
X0132850Y0421837
X0135245Y0407228
X0011000Y1239500
X0141327Y0398000
X0124378Y0409308
X0127900Y0367900
X0130200Y0337400
X0130200Y0339900
X0127900Y0351800
X0127800Y0370900
X0127900Y0364300
X0127900Y0345100
X0128000Y0348300
X0142727Y0428000
X0145327Y0416500
X0129314Y0414545
X0136000Y0429941
X0112441Y0418434
X0113000Y0394500
X0003005Y1310675
X0003005Y1290675
X0003005Y1270675
X0003005Y1250675
X0096017Y1323770
X0076017Y1323770
X0056017Y1323770
X0035517Y1323770
X0016017Y1323770
X0118500Y0403500
X0019500Y1239500
X0107000Y0389500
X0107000Y0400425
X0012150Y1227850
X0188516Y0518310
X0167190Y0529510
X0145193Y0504232
X0144324Y0498325
X0138532Y0507500
X0144335Y0509166
X0076400Y1188100
X0122000Y0463000
X0153725Y0514500
X0153725Y0524500
X0064425Y1165500
X0064850Y1179000
X0102075Y0534000
X0109000Y0485000
X0108500Y0512000
X0112070Y0499790
X0068686Y1139993
X0126070Y0493931
X0040500Y1164000
X0150575Y0534500
X0150575Y0509500
X0129000Y0468000
X0150575Y0504500
X0077518Y1138500
X0150575Y0519500
X0079000Y1173425
X0079000Y1157425
X0154000Y0471000
X0104500Y0478500
X0191500Y0529500
X0191575Y0524000
X0151635Y0476202
X0104500Y0483425
X0135000Y0463000
X0023500Y1237000
X0010241Y1234150
X0056000Y1203273
X0113500Y0476000
X0105732Y0496844
X0105815Y0488500
X0191575Y0518500
X0179000Y0535075
X0116000Y0529500
X0134000Y0501000
X0177000Y0514000
X0169000Y0514000
X0177000Y0522000
X0169000Y0522000
X0170000Y0504500
X0128000Y0504500
X0120000Y0504500
X0120000Y0512500
X0128000Y0512500
X0008000Y1222500
X0008000Y1220000
X0011000Y1215000
X0073505Y1200075
X0077773Y1147500
X0069018Y1147650
X0094730Y1173910
X0071150Y1165500
X0074313Y1178559
X0057500Y1181000
X0061000Y1172500
X0077518Y1142650
X0062216Y1139950
X0195500Y0497500
X0195500Y0495000
X0195000Y0490500
X0135349Y0468652
X0125200Y0453800
X0125500Y0469600
X0003005Y1230675
X0003005Y1210675
X0003005Y1190675
X0003005Y1170675
X0003005Y1150675
X0150500Y0489500
X0150575Y0499500
X0150575Y0529500
X0148000Y0483000
X0075000Y1196500
X0106850Y0441596
X0100835Y0446500
X0141500Y0516500
X0086000Y1176575
X0111000Y0506000
X0150575Y0524500
X0150575Y0494500
X0061500Y1160000
X0060475Y1152000
X0191991Y0536336
X0081000Y1193425
X0076500Y1162975
X0079106Y1176575
X0091000Y1173425
X0179000Y0531925
X0169000Y0535075
X0189500Y0512000
X0113500Y0523000
X0130000Y0485025
X0135500Y0485024
X0105760Y0493500
X0109000Y0500000
X0113500Y0485000
X0119000Y0485000
X0124500Y0485000
X0110500Y0445000
X0118490Y0495330
X0064843Y1194000
X0079500Y1134000
X0060185Y1041284
X0062765Y1041284
X0065265Y1041284
X0065265Y1043784
X0062725Y1043784
X0060185Y1043784
X0025000Y1107300
X0022000Y1107300
X0019000Y1107300
X0055635Y1094076
X0055635Y1090665
X0019000Y1104300
X0022000Y1104300
X0025000Y1104300
X0061029Y1060742
X0061029Y1064153
X0055701Y1068449
X0055701Y1071860
X0055700Y1075878
X0055700Y1079289
X0133491Y0560490
X0120000Y0581500
X0103037Y0624462
X0121500Y0557500
X0106977Y0561919
X0100505Y0561919
X0135500Y0562500
X0125000Y0562500
X0115788Y0573787
X0191259Y0547500
X0109000Y0543500
X0108000Y0539500
X0169000Y0542075
X0075893Y1061138
X0075860Y1064323
X0076526Y1069611
X0076464Y1072947
X0076464Y1079181
X0076526Y1075845
X0076493Y1091229
X0076431Y1094565
X0077816Y1128650
X0068543Y1128650
X0014000Y1062720
X0017000Y1062720
X0020000Y1062720
X0023000Y1062720
X0026000Y1062720
X0114000Y0591000
X0003005Y1130675
X0003005Y1110675
X0003005Y1090675
X0003005Y1070675
X0003005Y1050675
X0013492Y1046676
X0013492Y1051756
X0013492Y1049256
X0018185Y1038900
X0021385Y1038900
X0024685Y1038800
X0021385Y1041900
X0018185Y1041900
X0024685Y1041800
X0047981Y1038135
X0047981Y1040635
X0050521Y1040635
X0053061Y1040635
X0053061Y1038135
X0050561Y1038135
X0037585Y1041300
X0040585Y1041300
X0150575Y0539500
X0150500Y0544500
X0194000Y0550000
X0106000Y0634500
X0189250Y0541750
X0111000Y0555925
X0128500Y0554925
X0108601Y0627084
X0131500Y0634500
X0064231Y1115268
X0014587Y0956216
X0017127Y0956216
X0019667Y0956216
X0019667Y0958716
X0017087Y0958716
X0014587Y0958716
X0027587Y0937815
X0027886Y0972134
X0028791Y0976919
X0038500Y0977199
X0035259Y0968798
X0017500Y0974500
X0014791Y0976000
X0069802Y1006198
X0015000Y1001300
X0179000Y0676500
X0175475Y0668500
X0133575Y0692000
X0179000Y0694000
X0175500Y0672500
X0177500Y0679500
X0182500Y0688000
X0101309Y0675500
X0180500Y0684500
X0117500Y0689900
X0181000Y0696500
X0101284Y0671500
X0118000Y0696000
X0128000Y0694500
X0166547Y0663500
X0171977Y0656850
X0187500Y0643500
X0182500Y0641600
X0048664Y0994115
X0048664Y0991115
X0048664Y0988115
X0048664Y0985115
X0051164Y0985115
X0051164Y0988115
X0051164Y0991115
X0051164Y0994115
X0025500Y0977500
X0053000Y1021500
X0040555Y1027168
X0037555Y1027168
X0022985Y1012800
X0025985Y1012800
X0022985Y1015800
X0025985Y1015800
X0025985Y1028800
X0022985Y1028800
X0016985Y1012800
X0019985Y1012800
X0016985Y1015800
X0019985Y1015800
X0019985Y1028800
X0016985Y1028800
X0048005Y1012038
X0056245Y1004000
X0064108Y1006500
X0015275Y0995500
X0026500Y0997500
X0031791Y0993000
X0039367Y0972800
X0042367Y0972800
X0059367Y0996400
X0056367Y0996400
X0062367Y0996400
X0065367Y0996400
X0012053Y0937268
X0193475Y0706000
X0192582Y0733000
X0181475Y0713000
X0126500Y0706500
X0181475Y0720000
X0127983Y0736234
X0146000Y0729000
X0187050Y0663500
X0187050Y0659500
X0187050Y0652000
X0156962Y0692037
X0134575Y0659000
X0003005Y1030675
X0003005Y1010675
X0003005Y0990675
X0003005Y0970675
X0003005Y0950675
X0026791Y0959365
X0029331Y0959365
X0031871Y0959365
X0039167Y0958400
X0042167Y0958400
X0048731Y0957007
X0048731Y0959507
X0029291Y0961865
X0026791Y0961865
X0031871Y0961865
X0048631Y0962107
X0048631Y0964607
X0048631Y0967207
X0048631Y0969707
X0048731Y0974807
X0048731Y0972307
X0171580Y0716500
X0123401Y0669102
X0051852Y1012249
X0048492Y1006856
X0053000Y1026000
X0059268Y1007793
X0072000Y1013500
X0030522Y1000288
X0026990Y0975034
X0023009Y0995491
X0141900Y0645410
X0128065Y0725566
X0020000Y0989000
X0124499Y0660000
X0171440Y0708767
X0125075Y0715000
X0126185Y0688915
X0136500Y0728500
X0171586Y0735683
X0119000Y0734000
X0167642Y0682217
X0056150Y1007500
X0167679Y0674254
X0023702Y0992261
X0167060Y0692500
X0159051Y0671661
X0187925Y0701000
X0187041Y0730000
X0190300Y0725200
X0050000Y1023000
X0062500Y1025500
X0038880Y0989941
X0073000Y1010500
X0040972Y1010059
X0009838Y0994729
X0115525Y0731000
X0139150Y0712500
X0119500Y0715500
X0119500Y0707500
X0175500Y0651500
X0176000Y0659500
X0169475Y0720000
X0169475Y0713000
X0169475Y0706000
X0169475Y0733000
X0066000Y1025000
X0044100Y1027850
X0042000Y1023000
X0118079Y0639954
X0074000Y1026000
X0150300Y0645900
X0135000Y0637500
X0039061Y1005000
X0040500Y0995000
X0173200Y0770800
X0071410Y0846500
X0013500Y0862500
X0027587Y0934815
X0032825Y0914841
X0032825Y0917841
X0032625Y0928241
X0032625Y0925241
X0032525Y0907241
X0032525Y0904241
X0050808Y0883415
X0050808Y0880415
X0050808Y0877415
X0048308Y0883415
X0048308Y0880415
X0048308Y0877415
X0133900Y0776000
X0123000Y0829114
X0139075Y0801984
X0139650Y0785905
X0133246Y0811300
X0141088Y0804709
X0138428Y0806903
X0107365Y0776004
X0125654Y0772281
X0128500Y0786500
X0104500Y0834500
X0132370Y0788872
X0134800Y0826614
X0151300Y0756400
X0099000Y0853000
X0115563Y0759063
X0015664Y0873315
X0015664Y0876315
X0015664Y0879315
X0015600Y0870600
X0012800Y0870600
X0012864Y0879315
X0012864Y0876315
X0012864Y0873315
X0011700Y0925753
X0011700Y0928753
X0011700Y0915753
X0011700Y0918753
X0011700Y0904753
X0011700Y0907753
X0012053Y0934268
X0134525Y0815114
X0126000Y0834500
X0141327Y0822814
X0125227Y0815000
X0125500Y0820114
X0141993Y0800295
X0142727Y0791500
X0129705Y0777796
X0144827Y0763510
X0167075Y0756500
X0132350Y0793241
X0107500Y0782530
X0181475Y0747000
X0181475Y0740000
X0003005Y0930675
X0003005Y0910675
X0003005Y0890675
X0003005Y0870675
X0003005Y0850675
X0172000Y0751500
X0171500Y0743500
X0119836Y0761664
X0101500Y0824271
X0121536Y0749253
X0099000Y0848000
X0118711Y0797500
X0075500Y0852500
X0084000Y0844950
X0136500Y0742000
X0121841Y0775967
X0114857Y0741500
X0125352Y0749277
X0184425Y0738000
X0189000Y0758500
X0195000Y0752500
X0191000Y0756500
X0193000Y0754500
X0112294Y0754294
X0115525Y0738000
X0115525Y0745000
X0169475Y0740000
X0169475Y0747000
X0128500Y0791500
X0163925Y0756500
X0129285Y0781799
X0038900Y0800200
X0068000Y0804606
X0060000Y0797925
X0023000Y0760000
X0077000Y0823500
X0077400Y0775000
X0080000Y0828500
X0162877Y0913500
X0162877Y0924500
X0162877Y0921500
X0162877Y0934500
X0162877Y0931500
X0162877Y0910500
X0149864Y0896115
X0149864Y0893115
X0149864Y0890115
X0152364Y0896115
X0152364Y0893115
X0152364Y0890115
X0065350Y0818654
X0062058Y0801075
X0067993Y0827764
X0069000Y0771500
X0145600Y0838100
X0120500Y0845000
X0076725Y0749500
X0083000Y0810000
X0148281Y0838882
X0079975Y0739975
X0083000Y0804000
X0015012Y0745563
X0058612Y0740500
X0149500Y0850500
X0180264Y0889915
X0180264Y0892915
X0180264Y0895915
X0180264Y0898915
X0184377Y0913500
X0184377Y0910500
X0184377Y0924500
X0184377Y0921500
X0184377Y0934500
X0184377Y0931500
X0193964Y0899015
X0193964Y0896015
X0193964Y0893015
X0193964Y0890015
X0193964Y0887015
X0092950Y0821707
X0082000Y0833575
X0071650Y0821000
X0077018Y0836764
X0062216Y0830875
X0060773Y0820614
X0061000Y0810000
X0068694Y0764764
X0069018Y0783764
X0078000Y0782500
X0077816Y0764764
X0068481Y0800951
X0058673Y0775800
X0093000Y0745000
X0093025Y0738000
X0076500Y0746500
X0006025Y0741000
X0006025Y0748000
X0003005Y0830675
X0003005Y0810675
X0003005Y0790675
X0003005Y0770675
X0003005Y0750675
X0117500Y0857575
X0047813Y0833013
X0094000Y0818500
X0012819Y0751500
X0037000Y0756900
X0034000Y0757000
X0094000Y0825740
X0014830Y0763614
X0149000Y0854500
X0099500Y0787000
X0012419Y0765261
X0146000Y0854500
X0070925Y0749000
X0076475Y0742500
X0017500Y0748000
X0017500Y0741000
X0142999Y0842350
X0077000Y0819000
X0071500Y0805500
X0099279Y0781942
X0061576Y0762200
X0052800Y0813500
X0066000Y0776000
X0069350Y0711940
X0060000Y0696984
X0138278Y0959365
X0140818Y0959365
X0143358Y0959365
X0143358Y0961865
X0140778Y0961865
X0138278Y0961865
X0168177Y0943100
X0168177Y0940100
X0160732Y0977966
X0138605Y0977649
X0152823Y0978573
X0142000Y0977500
X0129112Y0978769
X0159000Y0972500
X0059475Y0688975
X0068000Y0676500
X0069000Y0669745
X0014925Y0663000
X0014925Y0690000
X0014925Y0669000
X0012500Y0679000
X0068000Y0664000
X0074075Y0726500
X0078677Y0637315
X0095032Y0660000
X0091532Y0663261
X0074075Y0721500
X0065570Y0734500
X0017458Y0737184
X0013375Y0730274
X0086000Y0688000
X0086000Y0696000
X0086000Y0680000
X0065552Y0645503
X0093000Y0731000
X0066400Y0655400
X0185285Y0982200
X0188285Y0982200
X0179285Y0982200
X0182285Y0982200
X0190158Y0998000
X0190158Y0995000
X0162500Y1023000
X0151000Y0981000
X0181658Y0998000
X0181658Y0995000
X0184658Y0998000
X0184658Y0995000
X0187658Y0998000
X0187658Y0995000
X0167758Y0976500
X0164758Y0976500
X0006000Y0727000
X0013425Y0712500
X0155482Y0996149
X0166358Y1004941
X0172905Y1006500
X0156858Y1007000
X0146482Y1028500
X0149482Y1028500
X0145982Y0998208
X0139435Y0996649
X0128882Y1015900
X0125882Y1015900
X0128882Y1012900
X0125882Y1012900
X0134882Y1015900
X0131882Y1015900
X0134882Y1012900
X0131882Y1012900
X0183177Y0943100
X0183177Y0940100
X0074075Y0732000
X0026500Y0732500
X0033500Y0694425
X0006025Y0734000
X0065475Y0679000
X0065475Y0685000
X0045240Y0682000
X0045240Y0669500
X0045240Y0657000
X0065500Y0671500
X0065475Y0666500
X0045500Y0646000
X0003005Y0730675
X0003005Y0710675
X0003005Y0690675
X0003005Y0670675
X0003005Y0650675
X0183758Y0969100
X0186658Y0969000
X0180658Y0969000
X0164858Y0961800
X0167858Y0961800
X0156162Y0962514
X0156162Y0965014
X0153582Y0965014
X0151082Y0965014
X0151082Y0962514
X0153622Y0962514
X0183758Y0953000
X0183758Y0956200
X0180658Y0952900
X0186658Y0952900
X0186658Y0956100
X0180658Y0956100
X0173858Y1025500
X0182058Y1022519
X0164337Y1002475
X0149658Y0974968
X0144482Y0995649
X0139435Y0989500
X0149500Y1023000
X0153150Y1028430
X0159500Y1023000
X0170929Y1024429
X0147229Y1004299
X0161884Y1026048
X0167858Y1007500
X0102500Y0979500
X0032728Y0679000
X0025023Y0669850
X0025023Y0663850
X0052977Y0681650
X0046950Y0672500
X0046950Y0666500
X0119500Y0992000
X0147393Y0995649
X0088300Y0639800
X0164947Y1007500
X0020327Y0711174
X0012512Y0647013
X0136482Y1002392
X0015713Y0710009
X0012000Y0641000
X0175858Y1000757
X0020453Y0708047
X0012389Y0653509
X0149769Y1010059
X0178811Y1007843
X0133529Y0995306
X0161581Y0995673
X0076475Y0715000
X0086000Y0700000
X0076500Y0709500
X0076500Y0704000
X0017500Y0734000
X0013000Y0709000
X0086000Y0684000
X0086000Y0676000
X0056475Y0685000
X0056475Y0660000
X0070925Y0732000
X0032760Y0682000
X0021525Y0672500
X0061500Y0728500
X0032760Y0669500
X0021525Y0654000
X0021525Y0660000
X0032760Y0657000
X0021525Y0666500
X0021000Y0644000
X0032258Y0646000
X0056475Y0672500
X0056475Y0679000
X0056475Y0666500
X0056475Y0647000
X0056475Y0641000
X0056475Y0654000
X0068100Y0721000
X0063070Y0652400
X0032720Y0660000
X0052977Y0662650
X0047499Y0649000
X0030380Y0648320
X0164600Y0998649
X0146644Y1007363
X0169358Y1013000
X0168982Y1041284
X0171562Y1041284
X0174062Y1041284
X0174062Y1043784
X0171522Y1043784
X0168982Y1043784
X0183458Y1106662
X0180458Y1106662
X0186458Y1106662
X0180458Y1103662
X0183458Y1103662
X0186458Y1103662
X0143072Y1097500
X0143072Y1095000
X0143072Y1092500
X0141572Y1070400
X0141572Y1067900
X0143072Y1078000
X0143072Y1075500
X0143072Y1073000
X0090680Y0561766
X0097000Y0569153
X0098780Y0617000
X0085000Y0562148
X0075396Y0544500
X0072500Y0541500
X0078457Y0634010
X0083300Y0624100
X0126793Y1067838
X0126760Y1071023
X0190358Y1060064
X0187358Y1060064
X0184358Y1060064
X0181358Y1060064
X0121072Y1097000
X0121072Y1072500
X0121072Y1075000
X0121072Y1077500
X0121072Y1092000
X0121072Y1094500
X0126500Y1129000
X0142088Y1131281
X0121000Y1128425
X0181358Y1062764
X0184358Y1062764
X0187358Y1062764
X0190358Y1062764
X0074857Y0611575
X0073500Y0562200
X0003005Y0630675
X0003005Y0610675
X0003005Y0590675
X0003005Y0570675
X0003005Y0550675
X0159358Y1038135
X0161858Y1038135
X0161858Y1040635
X0159318Y1040635
X0156778Y1040635
X0156778Y1038135
X0149482Y1043000
X0146482Y1043000
X0130382Y1039000
X0130382Y1042000
X0130382Y1055000
X0133382Y1039000
X0133382Y1042000
X0133382Y1055000
X0127182Y1039000
X0127182Y1042000
X0127182Y1055000
X0028900Y0556900
X0132175Y1117325
X0057000Y0538500
X0087500Y0634700
X0121000Y1131575
X0110000Y1128425
X0074000Y0608425
X0084050Y0555925
X0073747Y0570715
X0099051Y0635051
X0182600Y1228850
X0070500Y0443500
X0075650Y0517770
X0071300Y0460000
X0123000Y1181000
X0123500Y1137500
X0027580Y0528341
X0020452Y0513547
X0065350Y0447500
X0138650Y1165500
X0138650Y1149500
X0096275Y0519750
X0095184Y0493787
X0079293Y0523513
X0084723Y0532202
X0068000Y0463878
X0056925Y0488000
X0056925Y0493000
X0056925Y0518500
X0142500Y1176000
X0056925Y0523500
X0091593Y0439000
X0109500Y1139500
X0142500Y1161500
X0136800Y1194800
X0056925Y0503000
X0058500Y0441000
X0164000Y1171500
X0135800Y1138000
X0124500Y1148575
X0127000Y1166000
X0079500Y0449925
X0125440Y1175970
X0182741Y1235150
X0086500Y0481500
X0068500Y0537075
X0098925Y0512500
X0098925Y0524000
X0074500Y0475000
X0011000Y0506500
X0011000Y0515500
X0011000Y0520000
X0035484Y0534075
X0037500Y0512500
X0037500Y0520500
X0029500Y0512500
X0029500Y0520500
X0049250Y0516750
X0074626Y0515080
X0086500Y0504500
X0078500Y0504500
X0086500Y0512500
X0078500Y0512500
X0195500Y1222500
X0195500Y1220000
X0192500Y1215000
X0125000Y1198000
X0135000Y1197500
X0142500Y1183500
X0142727Y1151000
X0132350Y1156741
X0112941Y1146240
X0135500Y1143441
X0141649Y1141500
X0085500Y0472975
X0065250Y0470378
X0020500Y0495000
X0020500Y0497500
X0018000Y0491500
X0091059Y0452760
X0074979Y0437559
X0060773Y0457228
X0060773Y0443728
X0003005Y0530675
X0003005Y0510675
X0003005Y0490675
X0003005Y0470675
X0003005Y0450675
X0126360Y1185947
X0049689Y0474203
X0056925Y0508500
X0056925Y0528500
X0056925Y0498000
X0057000Y0483000
X0058500Y0454500
X0165500Y1229900
X0095000Y0462740
X0127000Y1157025
X0118000Y1151575
X0127000Y1143000
X0093000Y0531476
X0087500Y0531476
X0082000Y0531476
X0098925Y0534000
X0076500Y0531476
X0029500Y0534075
X0098925Y0515000
X0010987Y0523418
X0011000Y0511000
X0011000Y0502000
X0084575Y0487075
X0068345Y0533265
X0087500Y0522800
X0096502Y0501930
X0098040Y0506730
X0056925Y0533500
X0056925Y0513500
X0082500Y0398000
X0071000Y0427000
X0023500Y0361728
X0020500Y0361728
X0053000Y0369997
X0053000Y0367497
X0053000Y0364997
X0026500Y0361728
X0017500Y0361728
X0017500Y0358728
X0020500Y0358728
X0023500Y0358728
X0026500Y0358728
X0055700Y0342500
X0053000Y0350997
X0053000Y0348497
X0053000Y0345997
X0082000Y0415000
X0067000Y0430500
X0065900Y0413000
X0078500Y0406000
X0091500Y0434000
X0079463Y0429962
X0156017Y1323770
X0183500Y1240500
X0073300Y0338100
X0073300Y0340600
X0074700Y0348500
X0074428Y0365500
X0074428Y0368000
X0074700Y0351000
X0074428Y0370500
X0074700Y0346000
X0077773Y0420228
X0078500Y0410000
X0069018Y0420378
X0062216Y0412678
X0068700Y0400000
X0084500Y0404000
X0003005Y0430675
X0003005Y0410675
X0003005Y0390675
X0003005Y0370675
X0003005Y0350675
X0194471Y1321882
X0176017Y1323770
X0136017Y1323770
X0116017Y1323770
X0082500Y0389500
X0060475Y0429228
X0060475Y0424728
X0192000Y1240500
X0059685Y0314512
X0059685Y0317012
X0062225Y0317012
X0062265Y0314512
X0064765Y0317012
X0064765Y0314512
X0010500Y0274500
X0066561Y0273985
X0052167Y0256328
X0055167Y0256328
X0061167Y0256328
X0058167Y0256328
X0025545Y0248578
X0054926Y0296651
X0037185Y0301728
X0040185Y0301728
X0047561Y0280228
X0018185Y0289228
X0018185Y0286228
X0024185Y0289228
X0021185Y0289228
X0027185Y0289228
X0024185Y0286228
X0021185Y0286228
X0027185Y0286228
X0056730Y0278169
X0026000Y0335928
X0023000Y0335928
X0020000Y0335928
X0017000Y0335928
X0014000Y0335928
X0055167Y0272228
X0064167Y0272228
X0061167Y0272228
X0058167Y0272228
X0052167Y0259228
X0055167Y0259228
X0061167Y0259228
X0058167Y0259228
X0042167Y0244728
X0039167Y0244728
X0010000Y0267303
X0032000Y0261000
X0027912Y0270676
X0003005Y0330675
X0003005Y0310675
X0003005Y0290675
X0003005Y0270675
X0003005Y0250675
X0200536Y1249059
X0200536Y1269059
X0200536Y1289059
X0200536Y1309059
X0024185Y0315228
X0027185Y0315228
X0027185Y0312228
X0024185Y0312228
X0018185Y0315228
X0021185Y0315228
X0021185Y0312228
X0018185Y0312228
X0040185Y0316228
X0037185Y0316228
X0047481Y0313863
X0047481Y0311363
X0050061Y0311363
X0052561Y0311363
X0052561Y0313863
X0050021Y0313863
X0056967Y0246228
X0053967Y0246228
X0050967Y0246228
X0061420Y0299310
X0040500Y0295500
X0064561Y0298446
X0057430Y0298520
X0052000Y0298528
X0071689Y0302000
X0044500Y0301500
X0044500Y0272767
X0053343Y0301334
X0058561Y0280728
X0064500Y0287000
X0026040Y0245190
X0032716Y0273500
X0021500Y0267500
X0017953Y0267500
X0055650Y0280728
X0011800Y0284000
X0024000Y0276000
X0072500Y0283771
X0040472Y0283287
X0012791Y0261000
X0038880Y0263169
X0042309Y0251270
X0036880Y0249217
X0029390Y0246960
X0009400Y0241516
X0017782Y0248150
X0014791Y0247715
X0022170Y0246150
X0038383Y0280119
X0041864Y0265636
X0014587Y0229444
X0017127Y0229444
X0019667Y0229444
X0019667Y0231944
X0017087Y0231944
X0014587Y0231944
X0034480Y0199243
X0034544Y0189540
X0029191Y0207428
X0029191Y0210428
X0034480Y0202243
X0034544Y0192540
X0047487Y0174264
X0044487Y0174264
X0044487Y0171264
X0047487Y0171264
X0034380Y0179643
X0034380Y0182643
X0044399Y0146864
X0047399Y0146864
X0047399Y0152164
X0044399Y0152164
X0044399Y0149664
X0047399Y0149664
X0013580Y0198643
X0013580Y0201643
X0013080Y0189843
X0013080Y0192843
X0013080Y0179343
X0013080Y0182343
X0011208Y0170943
X0011208Y0173943
X0011874Y0154893
X0008908Y0160243
X0008908Y0163243
X0013708Y0170943
X0013708Y0173943
X0014791Y0207028
X0014791Y0210028
X0003005Y0230675
X0003005Y0210675
X0003005Y0190675
X0003005Y0170675
X0003005Y0150675
X0200536Y1149059
X0200536Y1169059
X0200536Y1189059
X0200536Y1209059
X0200536Y1229059
X0031871Y0232593
X0029331Y0232593
X0026791Y0232593
X0054456Y0230214
X0048456Y0230214
X0051456Y0230214
X0042167Y0230228
X0039167Y0230228
X0054477Y0233457
X0051477Y0233457
X0048477Y0233457
X0031871Y0235093
X0026791Y0235093
X0029291Y0235093
X0080500Y0074000
X0076743Y0116500
X0065350Y0102000
X0064025Y0092575
X0068416Y0063842
X0068500Y0070000
X0079500Y0104425
X0099883Y0057500
X0079500Y0086925
X0099000Y0061000
X0085500Y0040000
X0078400Y0040200
X0085500Y0043500
X0085500Y0047000
X0078400Y0043700
X0078400Y0047200
X0075500Y0130000
X0091059Y0094630
X0071650Y0111259
X0071650Y0094259
X0075173Y0078000
X0069100Y0076100
X0068508Y0050969
X0061300Y0066900
X0058700Y0110900
X0061500Y0097500
X0062716Y0129542
X0003005Y0130675
X0003005Y0110675
X0003005Y0090675
X0003005Y0070675
X0003005Y0050675
X0200536Y1049059
X0200536Y1069059
X0200536Y1089059
X0200536Y1109059
X0200536Y1129059
X0084400Y0064200
X0071500Y0130000
X0088900Y0119300
X0076000Y0133500
X0007500Y0044000
X0087500Y0083300
X0094430Y0103830
X0086000Y0092000
X0088802Y0100198
X0082975Y0053333
X0061000Y0084192
X0060475Y0079692
X0085500Y0033000
X0085500Y0036500
X0078400Y0033200
X0078400Y0036700
X0061802Y0025927
X0054927Y0003006
X0034927Y0003006
X0015868Y0003010
X0003005Y0030675
X0200536Y0947059
X0200536Y0969059
X0200536Y0989059
X0200536Y1009059
X0200536Y1029059
X0200536Y0849059
X0200536Y0869059
X0200536Y0889059
X0200536Y0909059
X0200536Y0929059
X0200536Y0749059
X0200536Y0769059
X0200536Y0789059
X0200536Y0809059
X0200536Y0829059
X0200536Y0649059
X0200536Y0669059
X0200536Y0689059
X0200536Y0709059
X0200536Y0729059
X0200536Y0549059
X0200536Y0569059
X0200536Y0589059
X0200536Y0609059
X0200536Y0629059
X0200536Y0449059
X0200536Y0469059
X0200536Y0489059
X0200536Y0509059
X0200536Y0529059
X0200536Y0349059
X0200536Y0369059
X0200536Y0389059
X0200536Y0409059
X0200536Y0429059
X0200536Y0249059
X0200536Y0269059
X0200536Y0289059
X0200536Y0309059
X0200536Y0329059
X0200536Y0149059
X0200536Y0169059
X0200536Y0189059
X0200536Y0209059
X0200536Y0229059
X0200536Y0049059
X0200536Y0069059
X0200536Y0089059
X0200536Y0109059
X0200536Y0129059
X0200536Y0029059
M00
X0177165Y0103976
X0177165Y0096102
X0177165Y0088228
X0177165Y0080354
X0177165Y0072480
X0177165Y0064606
X0177165Y0056732
X0177165Y0048858
X0169291Y0103976
X0169291Y0096102
X0169291Y0088228
X0169291Y0080354
X0169291Y0072480
X0169291Y0064606
X0169291Y0056732
X0169291Y0048858
X0177165Y0435866
X0177165Y0427992
X0177165Y0420118
X0177165Y0412244
X0169291Y0435866
X0169291Y0427992
X0169291Y0420118
X0169291Y0412244
X0026378Y1139016
X0026378Y1146890
X0026378Y1154764
X0026378Y1162638
X0026378Y1170512
X0026378Y1178386
X0026378Y1186260
X0026378Y1194134
X0034252Y1139016
X0034252Y1146890
X0034252Y1154764
X0034252Y1162638
X0034252Y1170512
X0034252Y1178386
X0034252Y1186260
X0034252Y1194134
X0177165Y0467362
X0177165Y0459488
X0177165Y0451614
X0177165Y0443740
X0169291Y0467362
X0169291Y0459488
X0169291Y0451614
X0169291Y0443740
X0177165Y0830748
X0177165Y0822874
X0177165Y0815000
X0177165Y0807126
X0177165Y0799252
X0177165Y0791378
X0177165Y0783504
X0177165Y0775630
X0169291Y0830748
X0169291Y0822874
X0169291Y0815000
X0169291Y0807126
X0169291Y0799252
X0169291Y0791378
X0169291Y0783504
X0169291Y0775630
X0026378Y0775630
X0026378Y0783504
X0026378Y0791378
X0026378Y0799252
X0026378Y0807126
X0026378Y0815000
X0026378Y0822874
X0026378Y0830748
X0034252Y0775630
X0034252Y0783504
X0034252Y0791378
X0034252Y0799252
X0034252Y0807126
X0034252Y0815000
X0034252Y0822874
X0034252Y0830748
X0026378Y0443740
X0026378Y0451614
X0026378Y0459488
X0026378Y0467362
X0034252Y0443740
X0034252Y0451614
X0034252Y0459488
X0034252Y0467362
X0177165Y1194134
X0177165Y1186260
X0177165Y1178386
X0177165Y1170512
X0177165Y1162638
X0177165Y1154764
X0177165Y1146890
X0177165Y1139016
X0169291Y1194134
X0169291Y1186260
X0169291Y1178386
X0169291Y1170512
X0169291Y1162638
X0169291Y1154764
X0169291Y1146890
X0169291Y1139016
X0026378Y0412244
X0026378Y0420118
X0026378Y0427992
X0026378Y0435866
X0034252Y0412244
X0034252Y0420118
X0034252Y0427992
X0034252Y0435866
X0026378Y0048858
X0026378Y0056732
X0026378Y0064606
X0026378Y0072480
X0026378Y0080354
X0026378Y0088228
X0026378Y0096102
X0026378Y0103976
X0034252Y0048858
X0034252Y0056732
X0034252Y0064606
X0034252Y0072480
X0034252Y0080354
X0034252Y0088228
X0034252Y0096102
X0034252Y0103976
M00
X-0063431Y0837184
X-0053431Y0837184
X-0058431Y0824000
X-0022318Y0837184
X-0032318Y0837184
X-0027318Y0824000
X-0063431Y1152816
X-0053431Y1152816
X-0058431Y1166000
X-0022318Y1152816
X-0032318Y1152816
X-0027318Y1166000
M00
X0101772Y0204370
X0160827Y0620713
X0101772Y0952401
X0042717Y0620713
M00
X0101772Y1287047
M00
X0173228Y0111456
X0173228Y0474842
X0030315Y1131536
X0030315Y0768150
X0173228Y0838228
X0173228Y1201614
X0030315Y0404764
X0030315Y0041378
M00
X0178500Y0017500
X0020000Y1307000
X0044000Y0017500
M30
